FILE_TYPE = MULTI_PHYS_TABLE;

PART 'FT4232HL_REEL_QFP64'
CLASS=IC

{========================================================================================}
:CLS_PN          | VALUE            = JEDEC_TYPE           | ALT_SYMBOLS            | DESCRIPTION                      | CPN_STATUS ;
{========================================================================================}
 'G223-10282-01' | 'FT4232HL-REEL'  = 'QFP64_394_P0197_V1' | '(QFP64_394_P0197_V1)' | 'IC,FT4232H,USB TO UART,LQFP-64' | ''        

END_PART

END.

